(kicad_pcb
	(version 20221018)
	(generator pcbnew)
	(general
    (thickness 1.62)
  )
	(paper "A4")
	(title_block
    (title "ECP5 - Datacenter Secure Control Module (DC-SCM)")
    (date "2024-07-01")
    (rev "1.2.1")
		(comment 9 "footprint 50 of 506 (U21), pads 204-300 of 756")
	)
	(layers
    (0 "F.Cu" signal)
    (1 "In1.Cu" power)
    (2 "In2.Cu" signal)
    (3 "In3.Cu" power)
    (4 "In4.Cu" power)
    (5 "In5.Cu" signal)
    (6 "In6.Cu" power)
    (31 "B.Cu" signal)
    (32 "B.Adhes" user "B.Adhesive")
    (33 "F.Adhes" user "F.Adhesive")
    (34 "B.Paste" user)
    (35 "F.Paste" user)
    (36 "B.SilkS" user "B.Silkscreen")
    (37 "F.SilkS" user "F.Silkscreen")
    (38 "B.Mask" user)
    (39 "F.Mask" user)
    (40 "Dwgs.User" user "User.Drawings")
    (41 "Cmts.User" user "User.Comments")
    (42 "Eco1.User" user "User.Eco1")
    (43 "Eco2.User" user "User.Eco2")
    (44 "Edge.Cuts" user)
    (45 "Margin" user)
    (46 "B.CrtYd" user "B.Courtyard")
    (47 "F.CrtYd" user "F.Courtyard")
    (48 "B.Fab" user)
    (49 "F.Fab" user)
  )
	(footprint "antmicro-footprints:BGA-1024-756_27x27mm_Layout32x32_P0.8mm" locked
    (layer "F.Cu")
    (at 104.4 120.55)
    (property "Author" "Antmicro")
    (property "License" "Apache-2.0")
    (property "MPN" "LFE5UM5G-85F-8BG756C")
    (property "Manufacturer" "Lattice Semiconductor")
    (property "Sheetfile" "fpga-power-supply.kicad_sch")
    (property "Sheetname" "FPGA power supply")
    (property "ki_description" "ECP5-5G Field Programmable Gate Array")
    (property "ki_keywords" "SMT, FPGA, IC")
    (attr smd)
    (fp_text reference "U21" (at -12.97 -14.53) (layer "F.SilkS")
        (effects (font (size 0.7 0.7) (thickness 0.127)))
    )
    (fp_text value "ECP5UM5G_85_CABGA756" (at 0 14.5) (layer "F.Fab")
        (effects (font (size 1 1) (thickness 0.15)))
    )
    (pad "AJ23" smd circle locked (at 5.2 10) (size 0.4 0.4) (layers "F.Cu" "F.Paste" "F.Mask")
      (net 1 "GND") (pinfunction "GND") (pintype "passive"))
    (pad "AJ24" smd circle locked (at 6 10) (size 0.4 0.4) (layers "F.Cu" "F.Paste" "F.Mask")
      (net 304 "/FPGA power supply/VCCAUX") (pinfunction "VCCAUXA1") (pintype "power_in"))
    (pad "AJ25" smd circle locked (at 6.8 10) (size 0.4 0.4) (layers "F.Cu" "F.Paste" "F.Mask")
      (net 304 "/FPGA power supply/VCCAUX") (pinfunction "VCCAUXA1") (pintype "passive"))
    (pad "AJ26" smd circle locked (at 7.6 10) (size 0.4 0.4) (layers "F.Cu" "F.Paste" "F.Mask")
      (net 1 "GND") (pinfunction "GND") (pintype "passive"))
    (pad "AJ28" smd circle locked (at 9.2 10) (size 0.4 0.4) (layers "F.Cu" "F.Paste" "F.Mask")
      (net 74 "NCSI_CLK") (pinfunction "PB112A") (pintype "bidirectional"))
    (pad "AJ29" smd circle locked (at 10 10) (size 0.4 0.4) (layers "F.Cu" "F.Paste" "F.Mask")
      (net 80 "NCSI_RXD0") (pinfunction "PB121A") (pintype "bidirectional"))
    (pad "AJ30" smd circle locked (at 10.8 10) (size 0.4 0.4) (layers "F.Cu" "F.Paste" "F.Mask")
      (net 86 "SGPIO1_DO") (pinfunction "PB121B") (pintype "bidirectional"))
    (pad "AJ31" smd circle locked (at 11.6 10) (size 0.4 0.4) (layers "F.Cu" "F.Paste" "F.Mask")
      (net 92 "QSPI1_CLK") (pinfunction "PB105B") (pintype "bidirectional"))
    (pad "AJ32" smd circle locked (at 12.4 10) (size 0.4 0.4) (layers "F.Cu" "F.Paste" "F.Mask")
      (net 89 "SGPIO_RESET_N") (pinfunction "PB101B") (pintype "bidirectional"))
    (pad "AK1" smd circle locked (at -12.4 10.8) (size 0.4 0.4) (layers "F.Cu" "F.Paste" "F.Mask")
      (net 429 "Net-(U21I-PB6B)") (pinfunction "PB6B") (pintype "bidirectional"))
    (pad "AK2" smd circle locked (at -11.6 10.8) (size 0.4 0.4) (layers "F.Cu" "F.Paste" "F.Mask")
      (net 276 "ROT_QSPI_DQ0") (pinfunction "PB11B") (pintype "bidirectional"))
    (pad "AK3" smd circle locked (at -10.8 10.8) (size 0.4 0.4) (layers "F.Cu" "F.Paste" "F.Mask")
      (net 102 "VIRTUAL_RESEAT") (pinfunction "PB15B") (pintype "bidirectional"))
    (pad "AK4" smd circle locked (at -10 10.8) (size 0.4 0.4) (layers "F.Cu" "F.Paste" "F.Mask")
      (net 576 "unconnected-(U21I-CFG_2-PadAK4)") (pinfunction "CFG_2") (pintype "bidirectional+no_connect"))
    (pad "AK5" smd circle locked (at -9.2 10.8) (size 0.4 0.4) (layers "F.Cu" "F.Paste" "F.Mask")
      (net 21 "JTAG_TCK") (pinfunction "TCK") (pintype "bidirectional"))
    (pad "AK7" smd circle locked (at -7.6 10.8) (size 0.4 0.4) (layers "F.Cu" "F.Paste" "F.Mask")
      (net 1 "GND") (pinfunction "GND") (pintype "passive"))
    (pad "AK8" smd circle locked (at -6.8 10.8) (size 0.4 0.4) (layers "F.Cu" "F.Paste" "F.Mask")
      (net 1 "GND") (pinfunction "GND") (pintype "passive"))
    (pad "AK9" smd circle locked (at -6 10.8) (size 0.4 0.4) (layers "F.Cu" "F.Paste" "F.Mask")
      (net 687 "/FPGA banks/PCIE_BMC_TX_C_DP") (pinfunction "HDTXP0_D0CH0") (pintype "bidirectional"))
    (pad "AK10" smd circle locked (at -5.2 10.8) (size 0.4 0.4) (layers "F.Cu" "F.Paste" "F.Mask")
      (net 686 "/FPGA banks/PCIE_BMC_TX_C_DN") (pinfunction "HDTXN0_D0CH0") (pintype "bidirectional"))
    (pad "AK11" smd circle locked (at -4.4 10.8) (size 0.4 0.4) (layers "F.Cu" "F.Paste" "F.Mask")
      (net 1 "GND") (pinfunction "GND") (pintype "passive"))
    (pad "AK12" smd circle locked (at -3.6 10.8) (size 0.4 0.4) (layers "F.Cu" "F.Paste" "F.Mask")
      (net 577 "unconnected-(U21K-HDTXP0_D0CH1-PadAK12)") (pinfunction "HDTXP0_D0CH1") (pintype "bidirectional+no_connect"))
    (pad "AK13" smd circle locked (at -2.8 10.8) (size 0.4 0.4) (layers "F.Cu" "F.Paste" "F.Mask")
      (net 578 "unconnected-(U21K-HDTXN0_D0CH1-PadAK13)") (pinfunction "HDTXN0_D0CH1") (pintype "bidirectional+no_connect"))
    (pad "AK14" smd circle locked (at -2 10.8) (size 0.4 0.4) (layers "F.Cu" "F.Paste" "F.Mask")
      (net 1 "GND") (pinfunction "GND") (pintype "passive"))
    (pad "AK15" smd circle locked (at -1.2 10.8) (size 0.4 0.4) (layers "F.Cu" "F.Paste" "F.Mask")
      (net 579 "unconnected-(U21A-RESERVED-PadAK15)") (pinfunction "RESERVED") (pintype "no_connect"))
    (pad "AK16" smd circle locked (at -0.4 10.8) (size 0.4 0.4) (layers "F.Cu" "F.Paste" "F.Mask")
      (net 580 "unconnected-(U21A-RESERVED-PadAK16)") (pinfunction "RESERVED") (pintype "no_connect"))
    (pad "AK17" smd circle locked (at 0.4 10.8) (size 0.4 0.4) (layers "F.Cu" "F.Paste" "F.Mask")
      (net 1 "GND") (pinfunction "GND") (pintype "passive"))
    (pad "AK18" smd circle locked (at 1.2 10.8) (size 0.4 0.4) (layers "F.Cu" "F.Paste" "F.Mask")
      (net 581 "unconnected-(U21L-HDTXP0_D1CH0-PadAK18)") (pinfunction "HDTXP0_D1CH0") (pintype "bidirectional+no_connect"))
    (pad "AK19" smd circle locked (at 2 10.8) (size 0.4 0.4) (layers "F.Cu" "F.Paste" "F.Mask")
      (net 582 "unconnected-(U21L-HDTXN0_D1CH0-PadAK19)") (pinfunction "HDTXN0_D1CH0") (pintype "bidirectional+no_connect"))
    (pad "AK20" smd circle locked (at 2.8 10.8) (size 0.4 0.4) (layers "F.Cu" "F.Paste" "F.Mask")
      (net 1 "GND") (pinfunction "GND") (pintype "passive"))
    (pad "AK21" smd circle locked (at 3.6 10.8) (size 0.4 0.4) (layers "F.Cu" "F.Paste" "F.Mask")
      (net 583 "unconnected-(U21L-HDTXP0_D1CH1-PadAK21)") (pinfunction "HDTXP0_D1CH1") (pintype "bidirectional+no_connect"))
    (pad "AK22" smd circle locked (at 4.4 10.8) (size 0.4 0.4) (layers "F.Cu" "F.Paste" "F.Mask")
      (net 584 "unconnected-(U21L-HDTXN0_D1CH1-PadAK22)") (pinfunction "HDTXN0_D1CH1") (pintype "bidirectional+no_connect"))
    (pad "AK23" smd circle locked (at 5.2 10.8) (size 0.4 0.4) (layers "F.Cu" "F.Paste" "F.Mask")
      (net 1 "GND") (pinfunction "GND") (pintype "passive"))
    (pad "AK24" smd circle locked (at 6 10.8) (size 0.4 0.4) (layers "F.Cu" "F.Paste" "F.Mask")
      (net 585 "unconnected-(U21A-RESERVED-PadAK24)") (pinfunction "RESERVED") (pintype "no_connect"))
    (pad "AK25" smd circle locked (at 6.8 10.8) (size 0.4 0.4) (layers "F.Cu" "F.Paste" "F.Mask")
      (net 586 "unconnected-(U21A-RESERVED-PadAK25)") (pinfunction "RESERVED") (pintype "no_connect"))
    (pad "AK26" smd circle locked (at 7.6 10.8) (size 0.4 0.4) (layers "F.Cu" "F.Paste" "F.Mask")
      (net 1 "GND") (pinfunction "GND") (pintype "passive"))
    (pad "AK28" smd circle locked (at 9.2 10.8) (size 0.4 0.4) (layers "F.Cu" "F.Paste" "F.Mask")
      (net 75 "NCSI_CRS_DV") (pinfunction "PB98B") (pintype "bidirectional"))
    (pad "AK29" smd circle locked (at 10 10.8) (size 0.4 0.4) (layers "F.Cu" "F.Paste" "F.Mask")
      (net 81 "NCSI_RXD1") (pinfunction "PB116A") (pintype "bidirectional"))
    (pad "AK30" smd circle locked (at 10.8 10.8) (size 0.4 0.4) (layers "F.Cu" "F.Paste" "F.Mask")
      (net 83 "SGPIO0_CLK") (pinfunction "PB116B") (pintype "bidirectional"))
    (pad "AK31" smd circle locked (at 11.6 10.8) (size 0.4 0.4) (layers "F.Cu" "F.Paste" "F.Mask")
      (net 87 "SGPIO1_DI") (pinfunction "PB105A") (pintype "bidirectional"))
    (pad "AK32" smd circle locked (at 12.4 10.8) (size 0.4 0.4) (layers "F.Cu" "F.Paste" "F.Mask")
      (net 93 "QSPI1_CS0_N") (pinfunction "PB101A") (pintype "bidirectional"))
    (pad "AL1" smd circle locked (at -12.4 11.6) (size 0.4 0.4) (layers "F.Cu" "F.Paste" "F.Mask")
      (net 273 "ROT_QSPI_DQ3") (pinfunction "PB9A") (pintype "bidirectional"))
    (pad "AL2" smd circle locked (at -11.6 11.6) (size 0.4 0.4) (layers "F.Cu" "F.Paste" "F.Mask")
      (net 1 "GND") (pinfunction "GND") (pintype "passive"))
    (pad "AL3" smd circle locked (at -10.8 11.6) (size 0.4 0.4) (layers "F.Cu" "F.Paste" "F.Mask")
      (net 58 "PRSNT0_N") (pinfunction "PB18A") (pintype "bidirectional"))
    (pad "AL4" smd circle locked (at -10 11.6) (size 0.4 0.4) (layers "F.Cu" "F.Paste" "F.Mask")
      (net 587 "unconnected-(U21I-CFG_1-PadAL4)") (pinfunction "CFG_1") (pintype "bidirectional+no_connect"))
    (pad "AL5" smd circle locked (at -9.2 11.6) (size 0.4 0.4) (layers "F.Cu" "F.Paste" "F.Mask")
      (net 1 "GND") (pinfunction "GND") (pintype "passive"))
    (pad "AL7" smd circle locked (at -7.6 11.6) (size 0.4 0.4) (layers "F.Cu" "F.Paste" "F.Mask")
      (net 1 "GND") (pinfunction "GND") (pintype "passive"))
    (pad "AL8" smd circle locked (at -6.8 11.6) (size 0.4 0.4) (layers "F.Cu" "F.Paste" "F.Mask")
      (net 1 "GND") (pinfunction "GND") (pintype "passive"))
    (pad "AL9" smd circle locked (at -6 11.6) (size 0.4 0.4) (layers "F.Cu" "F.Paste" "F.Mask")
      (net 1 "GND") (pinfunction "GND") (pintype "passive"))
    (pad "AL11" smd circle locked (at -4.4 11.6) (size 0.4 0.4) (layers "F.Cu" "F.Paste" "F.Mask")
      (net 1 "GND") (pinfunction "GND") (pintype "passive"))
    (pad "AL12" smd circle locked (at -3.6 11.6) (size 0.4 0.4) (layers "F.Cu" "F.Paste" "F.Mask")
      (net 1 "GND") (pinfunction "GND") (pintype "passive"))
    (pad "AL14" smd circle locked (at -2 11.6) (size 0.4 0.4) (layers "F.Cu" "F.Paste" "F.Mask")
      (net 1 "GND") (pinfunction "GND") (pintype "passive"))
    (pad "AL15" smd circle locked (at -1.2 11.6) (size 0.4 0.4) (layers "F.Cu" "F.Paste" "F.Mask")
      (net 1 "GND") (pinfunction "GND") (pintype "passive"))
    (pad "AL17" smd circle locked (at 0.4 11.6) (size 0.4 0.4) (layers "F.Cu" "F.Paste" "F.Mask")
      (net 1 "GND") (pinfunction "GND") (pintype "passive"))
    (pad "AL18" smd circle locked (at 1.2 11.6) (size 0.4 0.4) (layers "F.Cu" "F.Paste" "F.Mask")
      (net 1 "GND") (pinfunction "GND") (pintype "passive"))
    (pad "AL20" smd circle locked (at 2.8 11.6) (size 0.4 0.4) (layers "F.Cu" "F.Paste" "F.Mask")
      (net 1 "GND") (pinfunction "GND") (pintype "passive"))
    (pad "AL21" smd circle locked (at 3.6 11.6) (size 0.4 0.4) (layers "F.Cu" "F.Paste" "F.Mask")
      (net 1 "GND") (pinfunction "GND") (pintype "passive"))
    (pad "AL23" smd circle locked (at 5.2 11.6) (size 0.4 0.4) (layers "F.Cu" "F.Paste" "F.Mask")
      (net 1 "GND") (pinfunction "GND") (pintype "passive"))
    (pad "AL24" smd circle locked (at 6 11.6) (size 0.4 0.4) (layers "F.Cu" "F.Paste" "F.Mask")
      (net 1 "GND") (pinfunction "GND") (pintype "passive"))
    (pad "AL26" smd circle locked (at 7.6 11.6) (size 0.4 0.4) (layers "F.Cu" "F.Paste" "F.Mask")
      (net 1 "GND") (pinfunction "GND") (pintype "passive"))
    (pad "AL28" smd circle locked (at 9.2 11.6) (size 0.4 0.4) (layers "F.Cu" "F.Paste" "F.Mask")
      (net 76 "NCSI_TXEN") (pinfunction "PB98A") (pintype "bidirectional"))
    (pad "AL29" smd circle locked (at 10 11.6) (size 0.4 0.4) (layers "F.Cu" "F.Paste" "F.Mask")
      (net 1 "GND") (pinfunction "GND") (pintype "passive"))
    (pad "AL30" smd circle locked (at 10.8 11.6) (size 0.4 0.4) (layers "F.Cu" "F.Paste" "F.Mask")
      (net 85 "SGPIO0_LD") (pinfunction "PB103B") (pintype "bidirectional"))
    (pad "AL31" smd circle locked (at 11.6 11.6) (size 0.4 0.4) (layers "F.Cu" "F.Paste" "F.Mask")
      (net 1 "GND") (pinfunction "GND") (pintype "passive"))
    (pad "AL32" smd circle locked (at 12.4 11.6) (size 0.4 0.4) (layers "F.Cu" "F.Paste" "F.Mask")
      (net 88 "SGPIO1_LD") (pinfunction "PB107B") (pintype "bidirectional"))
    (pad "AM2" smd circle locked (at -11.6 12.4) (size 0.4 0.4) (layers "F.Cu" "F.Paste" "F.Mask")
      (net 274 "ROT_QSPI_DQ2") (pinfunction "PB9B") (pintype "bidirectional"))
    (pad "AM3" smd circle locked (at -10.8 12.4) (size 0.4 0.4) (layers "F.Cu" "F.Paste" "F.Mask")
      (net 272 "ROT_QSPI_SCK") (pinfunction "CCLK") (pintype "bidirectional"))
    (pad "AM4" smd circle locked (at -10 12.4) (size 0.4 0.4) (layers "F.Cu" "F.Paste" "F.Mask")
      (net 588 "unconnected-(U21I-CFG_0-PadAM4)") (pinfunction "CFG_0") (pintype "bidirectional+no_connect"))
    (pad "AM5" smd circle locked (at -9.2 12.4) (size 0.4 0.4) (layers "F.Cu" "F.Paste" "F.Mask")
      (net 22 "JTAG_TMS") (pinfunction "TMS") (pintype "bidirectional"))
    (pad "AM7" smd circle locked (at -7.6 12.4) (size 0.4 0.4) (layers "F.Cu" "F.Paste" "F.Mask")
      (net 1 "GND") (pinfunction "GND") (pintype "passive"))
    (pad "AM8" smd circle locked (at -6.8 12.4) (size 0.4 0.4) (layers "F.Cu" "F.Paste" "F.Mask")
      (net 107 "PCIE_BMC_RX_DP") (pinfunction "HDRXP0_D0CH0") (pintype "bidirectional"))
    (pad "AM9" smd circle locked (at -6 12.4) (size 0.4 0.4) (layers "F.Cu" "F.Paste" "F.Mask")
      (net 108 "PCIE_BMC_RX_DN") (pinfunction "HDRXN0_D0CH0") (pintype "bidirectional"))
    (pad "AM11" smd circle locked (at -4.4 12.4) (size 0.4 0.4) (layers "F.Cu" "F.Paste" "F.Mask")
      (net 589 "unconnected-(U21K-HDRXP0_D0CH1-PadAM11)") (pinfunction "HDRXP0_D0CH1") (pintype "bidirectional+no_connect"))
    (pad "AM12" smd circle locked (at -3.6 12.4) (size 0.4 0.4) (layers "F.Cu" "F.Paste" "F.Mask")
      (net 590 "unconnected-(U21K-HDRXN0_D0CH1-PadAM12)") (pinfunction "HDRXN0_D0CH1") (pintype "bidirectional+no_connect"))
    (pad "AM14" smd circle locked (at -2 12.4) (size 0.4 0.4) (layers "F.Cu" "F.Paste" "F.Mask")
      (net 103 "CLK_100M_PCIE_DP") (pinfunction "REFCLKP_D0") (pintype "bidirectional"))
    (pad "AM15" smd circle locked (at -1.2 12.4) (size 0.4 0.4) (layers "F.Cu" "F.Paste" "F.Mask")
      (net 104 "CLK_100M_PCIE_DN") (pinfunction "REFCLKN_D0") (pintype "bidirectional"))
    (pad "AM17" smd circle locked (at 0.4 12.4) (size 0.4 0.4) (layers "F.Cu" "F.Paste" "F.Mask")
      (net 591 "unconnected-(U21L-HDRXP0_D1CH0-PadAM17)") (pinfunction "HDRXP0_D1CH0") (pintype "bidirectional+no_connect"))
    (pad "AM18" smd circle locked (at 1.2 12.4) (size 0.4 0.4) (layers "F.Cu" "F.Paste" "F.Mask")
      (net 592 "unconnected-(U21L-HDRXN0_D1CH0-PadAM18)") (pinfunction "HDRXN0_D1CH0") (pintype "bidirectional+no_connect"))
    (pad "AM20" smd circle locked (at 2.8 12.4) (size 0.4 0.4) (layers "F.Cu" "F.Paste" "F.Mask")
      (net 593 "unconnected-(U21L-HDRXP0_D1CH1-PadAM20)") (pinfunction "HDRXP0_D1CH1") (pintype "bidirectional+no_connect"))
    (pad "AM21" smd circle locked (at 3.6 12.4) (size 0.4 0.4) (layers "F.Cu" "F.Paste" "F.Mask")
      (net 594 "unconnected-(U21L-HDRXN0_D1CH1-PadAM21)") (pinfunction "HDRXN0_D1CH1") (pintype "bidirectional+no_connect"))
    (pad "AM23" smd circle locked (at 5.2 12.4) (size 0.4 0.4) (layers "F.Cu" "F.Paste" "F.Mask")
      (net 595 "unconnected-(U21L-REFCLKP_D1-PadAM23)") (pinfunction "REFCLKP_D1") (pintype "bidirectional+no_connect"))
    (pad "AM24" smd circle locked (at 6 12.4) (size 0.4 0.4) (layers "F.Cu" "F.Paste" "F.Mask")
      (net 596 "unconnected-(U21L-REFCLKN_D1-PadAM24)") (pinfunction "REFCLKN_D1") (pintype "bidirectional+no_connect"))
    (pad "AM26" smd circle locked (at 7.6 12.4) (size 0.4 0.4) (layers "F.Cu" "F.Paste" "F.Mask")
      (net 1 "GND") (pinfunction "GND") (pintype "passive"))
    (pad "AM28" smd circle locked (at 9.2 12.4) (size 0.4 0.4) (layers "F.Cu" "F.Paste" "F.Mask")
      (net 77 "NCSI_TXD0") (pinfunction "PB96A") (pintype "bidirectional"))
    (pad "AM29" smd circle locked (at 10 12.4) (size 0.4 0.4) (layers "F.Cu" "F.Paste" "F.Mask")
      (net 82 "SGPIO0_DO") (pinfunction "PB96B") (pintype "bidirectional"))
    (pad "AM30" smd circle locked (at 10.8 12.4) (size 0.4 0.4) (layers "F.Cu" "F.Paste" "F.Mask")
      (net 84 "SGPIO0_DI") (pinfunction "PB103A") (pintype "bidirectional"))
    (pad "AM31" smd circle locked (at 11.6 12.4) (size 0.4 0.4) (layers "F.Cu" "F.Paste" "F.Mask")
      (net 277 "SGPIO1_CLK") (pinfunction "PB107A") (pintype "bidirectional"))
    (pad "B1" smd circle locked (at -12.4 -11.6) (size 0.4 0.4) (layers "F.Cu" "F.Paste" "F.Mask")
      (net 666 "ROT_GPIO1") (pinfunction "PL17A") (pintype "bidirectional"))
    (pad "B2" smd circle locked (at -11.6 -11.6) (size 0.4 0.4) (layers "F.Cu" "F.Paste" "F.Mask")
      (net 1 "GND") (pinfunction "GND") (pintype "passive"))
    (pad "B3" smd circle locked (at -10.8 -11.6) (size 0.4 0.4) (layers "F.Cu" "F.Paste" "F.Mask")
      (net 597 "unconnected-(U21B-PT4A-PadB3)") (pinfunction "PT4A") (pintype "bidirectional+no_connect"))
    (pad "B4" smd circle locked (at -10 -11.6) (size 0.4 0.4) (layers "F.Cu" "F.Paste" "F.Mask")
      (net 598 "unconnected-(U21B-PT4B-PadB4)") (pinfunction "PT4B") (pintype "bidirectional+no_connect"))
    (pad "B5" smd circle locked (at -9.2 -11.6) (size 0.4 0.4) (layers "F.Cu" "F.Paste" "F.Mask")
      (net 1 "GND") (pinfunction "GND") (pintype "passive"))
    (pad "B7" smd circle locked (at -7.6 -11.6) (size 0.4 0.4) (layers "F.Cu" "F.Paste" "F.Mask")
      (net 599 "unconnected-(U21B-PT13A-PadB7)") (pinfunction "PT13A") (pintype "bidirectional+no_connect"))
    (pad "B8" smd circle locked (at -6.8 -11.6) (size 0.4 0.4) (layers "F.Cu" "F.Paste" "F.Mask")
      (net 199 "RGMII_TXD2") (pinfunction "PT20A") (pintype "bidirectional"))
    (pad "B9" smd circle locked (at -6 -11.6) (size 0.4 0.4) (layers "F.Cu" "F.Paste" "F.Mask")
      (net 1 "GND") (pinfunction "GND") (pintype "passive"))
    (pad "B10" smd circle locked (at -5.2 -11.6) (size 0.4 0.4) (layers "F.Cu" "F.Paste" "F.Mask")
      (net 600 "unconnected-(U21B-PT31A-PadB10)") (pinfunction "PT31A") (pintype "bidirectional+no_connect"))
    (pad "B11" smd circle locked (at -4.4 -11.6) (size 0.4 0.4) (layers "F.Cu" "F.Paste" "F.Mask")
      (net 601 "unconnected-(U21B-PT38A-PadB11)") (pinfunction "PT38A") (pintype "bidirectional+no_connect"))
    (pad "B13" smd circle locked (at -2.8 -11.6) (size 0.4 0.4) (layers "F.Cu" "F.Paste" "F.Mask")
      (net 1 "GND") (pinfunction "GND") (pintype "passive"))
    (pad "B14" smd circle locked (at -2 -11.6) (size 0.4 0.4) (layers "F.Cu" "F.Paste" "F.Mask")
      (net 602 "unconnected-(U21B-PT49A-PadB14)") (pinfunction "PT49A") (pintype "bidirectional+no_connect"))
  )
)
